(kicad_pcb
	(version 20260206)
	(generator "pcbnew")
	(generator_version "10.0")
	(general
		(thickness 1.6)
		(legacy_teardrops no)
	)
	(paper "A4")
	(title_block
		(title "12092022_DA0F0TMDCD0_F0T_Management_Board_D_brd_V3_OCP.brd")
		(comment 1 "Grand Teton / footprints 553-557 of 1440")
	)
	(layers
		(0 "F.Cu" signal "TOP")
		(4 "In1.Cu" signal "GND")
		(6 "In2.Cu" signal "IN1")
		(8 "In3.Cu" signal "GND1")
		(10 "In4.Cu" signal "IN2")
		(12 "In5.Cu" signal "VCC")
		(14 "In6.Cu" signal "VCC1")
		(16 "In7.Cu" signal "IN3")
		(18 "In8.Cu" signal "GND2")
		(20 "In9.Cu" signal "IN4")
		(22 "In10.Cu" signal "GND3")
		(2 "B.Cu" signal "BOTTOM")
		(9 "F.Adhes" user "F.Adhesive")
		(11 "B.Adhes" user "B.Adhesive")
		(13 "F.Paste" user "Package Geometry/Pastemask Top")
		(15 "B.Paste" user "Package Geometry/Pastemask Bottom")
		(5 "F.SilkS" user "Ref Des/Silkscreen Top")
		(7 "B.SilkS" user "Ref Des/Silkscreen Bottom")
		(1 "F.Mask" user "Board Geometry/Soldermask Top")
		(3 "B.Mask" user "Board Geometry/Soldermask Bottom")
		(17 "Dwgs.User" user "User.Drawings")
		(19 "Cmts.User" user "User.Comments")
		(21 "Eco1.User" user "User.Eco1")
		(23 "Eco2.User" user "User.Eco2")
		(25 "Edge.Cuts" user "Board Geometry/Outline")
		(27 "Margin" user)
		(31 "F.CrtYd" user "Package Geometry/Place Bound Top")
		(29 "B.CrtYd" user "Package Geometry/Place Bound Bottom")
		(35 "F.Fab" user "Ref Des/Assembly Top")
		(33 "B.Fab" user "Ref Des/Assembly Bottom")
	)
	(footprint ""
		(layer "F.Cu")
		(at 63.105792 -65.37071)
		(property "Reference" "R116"
			(at 0 0 0)
			(layer "F.SilkS")
			(hide yes)
			(effects
				(font
					(size 1.27 1.27)
				)
			)
		)
		(property "Value" ""
			(at 0 0 0)
			(layer "F.Fab")
			(effects
				(font
					(size 1.27 1.27)
				)
			)
		)
		(duplicate_pad_numbers_are_jumpers no)
		(fp_line
			(start -0.7874 -0.4064)
			(end 0.7874 -0.4064)
			(stroke
				(width 0.1524)
				(type default)
			)
			(layer "F.SilkS")
		)
		(fp_line
			(start -0.7874 0.4064)
			(end -0.7874 -0.4064)
			(stroke
				(width 0.1524)
				(type default)
			)
			(layer "F.SilkS")
		)
		(fp_line
			(start 0.7874 -0.4064)
			(end 0.7874 0.4064)
			(stroke
				(width 0.1524)
				(type default)
			)
			(layer "F.SilkS")
		)
		(fp_line
			(start 0.7874 0.4064)
			(end -0.7874 0.4064)
			(stroke
				(width 0.1524)
				(type default)
			)
			(layer "F.SilkS")
		)
		(fp_line
			(start -0.67945 -0.305054)
			(end -0.12065 -0.305054)
			(stroke
				(width 0.1)
				(type default)
			)
			(layer "F.Fab")
		)
		(fp_line
			(start -0.67945 0.3048)
			(end -0.67945 -0.305054)
			(stroke
				(width 0.1)
				(type default)
			)
			(layer "F.Fab")
		)
		(fp_line
			(start -0.12065 -0.305054)
			(end -0.12065 -0.2794)
			(stroke
				(width 0.1)
				(type default)
			)
			(layer "F.Fab")
		)
		(fp_line
			(start -0.12065 -0.2794)
			(end 0.12065 -0.2794)
			(stroke
				(width 0.1)
				(type default)
			)
			(layer "F.Fab")
		)
		(fp_line
			(start -0.12065 0.2794)
			(end -0.12065 0.3048)
			(stroke
				(width 0.1)
				(type default)
			)
			(layer "F.Fab")
		)
		(fp_line
			(start -0.12065 0.3048)
			(end -0.67945 0.3048)
			(stroke
				(width 0.1)
				(type default)
			)
			(layer "F.Fab")
		)
		(fp_line
			(start 0.120396 0.2794)
			(end -0.12065 0.2794)
			(stroke
				(width 0.1)
				(type default)
			)
			(layer "F.Fab")
		)
		(fp_line
			(start 0.120396 0.3048)
			(end 0.120396 0.2794)
			(stroke
				(width 0.1)
				(type default)
			)
			(layer "F.Fab")
		)
		(fp_line
			(start 0.12065 -0.3048)
			(end 0.67945 -0.3048)
			(stroke
				(width 0.1)
				(type default)
			)
			(layer "F.Fab")
		)
		(fp_line
			(start 0.12065 -0.2794)
			(end 0.12065 -0.3048)
			(stroke
				(width 0.1)
				(type default)
			)
			(layer "F.Fab")
		)
		(fp_line
			(start 0.67945 -0.3048)
			(end 0.67945 0.3048)
			(stroke
				(width 0.1)
				(type default)
			)
			(layer "F.Fab")
		)
		(fp_line
			(start 0.67945 0.3048)
			(end 0.120396 0.3048)
			(stroke
				(width 0.1)
				(type default)
			)
			(layer "F.Fab")
		)
		(pad "1" smd circle
			(at -0.40005 0)
			(size 0 0)
			(layers "F.Cu" "F.Mask" "F.Paste")
			(net "PGPPA_BMC_AUX")
		)
		(pad "2" smd circle
			(at 0.40005 0)
			(size 0 0)
			(layers "F.Cu" "F.Mask" "F.Paste")
			(net "IRQ_BMC_LPC_SERIRQ_ESPI_GF")
		)
	)
	(footprint ""
		(layer "F.Cu")
		(at 64.51854 -108.004356 90)
		(property "Reference" "R115"
			(at 0 0 90)
			(layer "F.SilkS")
			(hide yes)
			(effects
				(font
					(size 1.27 1.27)
				)
			)
		)
		(property "Value" ""
			(at 0 0 90)
			(layer "F.Fab")
			(effects
				(font
					(size 1.27 1.27)
				)
			)
		)
		(duplicate_pad_numbers_are_jumpers no)
		(fp_line
			(start 0.7874 -0.4064)
			(end 0.7874 0.4064)
			(stroke
				(width 0.1524)
				(type default)
			)
			(layer "F.SilkS")
		)
		(fp_line
			(start -0.7874 -0.4064)
			(end 0.7874 -0.4064)
			(stroke
				(width 0.1524)
				(type default)
			)
			(layer "F.SilkS")
		)
		(fp_line
			(start 0.7874 0.4064)
			(end -0.7874 0.4064)
			(stroke
				(width 0.1524)
				(type default)
			)
			(layer "F.SilkS")
		)
		(fp_line
			(start -0.7874 0.4064)
			(end -0.7874 -0.4064)
			(stroke
				(width 0.1524)
				(type default)
			)
			(layer "F.SilkS")
		)
		(fp_line
			(start -0.12065 -0.305054)
			(end -0.12065 -0.2794)
			(stroke
				(width 0.1)
				(type default)
			)
			(layer "F.Fab")
		)
		(fp_line
			(start -0.67945 -0.305054)
			(end -0.12065 -0.305054)
			(stroke
				(width 0.1)
				(type default)
			)
			(layer "F.Fab")
		)
		(fp_line
			(start 0.67945 -0.3048)
			(end 0.67945 0.3048)
			(stroke
				(width 0.1)
				(type default)
			)
			(layer "F.Fab")
		)
		(fp_line
			(start 0.12065 -0.3048)
			(end 0.67945 -0.3048)
			(stroke
				(width 0.1)
				(type default)
			)
			(layer "F.Fab")
		)
		(fp_line
			(start 0.12065 -0.2794)
			(end 0.12065 -0.3048)
			(stroke
				(width 0.1)
				(type default)
			)
			(layer "F.Fab")
		)
		(fp_line
			(start -0.12065 -0.2794)
			(end 0.12065 -0.2794)
			(stroke
				(width 0.1)
				(type default)
			)
			(layer "F.Fab")
		)
		(fp_line
			(start 0.120396 0.2794)
			(end -0.12065 0.2794)
			(stroke
				(width 0.1)
				(type default)
			)
			(layer "F.Fab")
		)
		(fp_line
			(start -0.12065 0.2794)
			(end -0.12065 0.3048)
			(stroke
				(width 0.1)
				(type default)
			)
			(layer "F.Fab")
		)
		(fp_line
			(start 0.67945 0.3048)
			(end 0.120396 0.3048)
			(stroke
				(width 0.1)
				(type default)
			)
			(layer "F.Fab")
		)
		(fp_line
			(start 0.120396 0.3048)
			(end 0.120396 0.2794)
			(stroke
				(width 0.1)
				(type default)
			)
			(layer "F.Fab")
		)
		(fp_line
			(start -0.12065 0.3048)
			(end -0.67945 0.3048)
			(stroke
				(width 0.1)
				(type default)
			)
			(layer "F.Fab")
		)
		(fp_line
			(start -0.67945 0.3048)
			(end -0.67945 -0.305054)
			(stroke
				(width 0.1)
				(type default)
			)
			(layer "F.Fab")
		)
		(pad "1" smd circle
			(at -0.40005 0 90)
			(size 0 0)
			(layers "F.Cu" "F.Mask" "F.Paste")
			(net "PGPPA_BMC_AUX")
		)
		(pad "2" smd circle
			(at 0.40005 0 90)
			(size 0 0)
			(layers "F.Cu" "F.Mask" "F.Paste")
			(net "ESPI_HOST_LPC_BMC_LFRAME_N")
		)
	)
	(footprint ""
		(layer "F.Cu")
		(at 55.7276 -105.664 180)
		(property "Reference" "R501"
			(at 0 0 180)
			(layer "F.SilkS")
			(hide yes)
			(effects
				(font
					(size 1.27 1.27)
				)
			)
		)
		(property "Value" ""
			(at 0 0 180)
			(layer "F.Fab")
			(effects
				(font
					(size 1.27 1.27)
				)
			)
		)
		(duplicate_pad_numbers_are_jumpers no)
		(fp_line
			(start 0.7874 0.4064)
			(end -0.7874 0.4064)
			(stroke
				(width 0.1524)
				(type default)
			)
			(layer "F.SilkS")
		)
		(fp_line
			(start 0.7874 -0.4064)
			(end 0.7874 0.4064)
			(stroke
				(width 0.1524)
				(type default)
			)
			(layer "F.SilkS")
		)
		(fp_line
			(start -0.7874 0.4064)
			(end -0.7874 -0.4064)
			(stroke
				(width 0.1524)
				(type default)
			)
			(layer "F.SilkS")
		)
		(fp_line
			(start -0.7874 -0.4064)
			(end 0.7874 -0.4064)
			(stroke
				(width 0.1524)
				(type default)
			)
			(layer "F.SilkS")
		)
		(fp_line
			(start 0.67945 0.3048)
			(end 0.120396 0.3048)
			(stroke
				(width 0.1)
				(type default)
			)
			(layer "F.Fab")
		)
		(fp_line
			(start 0.67945 -0.3048)
			(end 0.67945 0.3048)
			(stroke
				(width 0.1)
				(type default)
			)
			(layer "F.Fab")
		)
		(fp_line
			(start 0.12065 -0.2794)
			(end 0.12065 -0.3048)
			(stroke
				(width 0.1)
				(type default)
			)
			(layer "F.Fab")
		)
		(fp_line
			(start 0.12065 -0.3048)
			(end 0.67945 -0.3048)
			(stroke
				(width 0.1)
				(type default)
			)
			(layer "F.Fab")
		)
		(fp_line
			(start 0.120396 0.3048)
			(end 0.120396 0.2794)
			(stroke
				(width 0.1)
				(type default)
			)
			(layer "F.Fab")
		)
		(fp_line
			(start 0.120396 0.2794)
			(end -0.12065 0.2794)
			(stroke
				(width 0.1)
				(type default)
			)
			(layer "F.Fab")
		)
		(fp_line
			(start -0.12065 0.3048)
			(end -0.67945 0.3048)
			(stroke
				(width 0.1)
				(type default)
			)
			(layer "F.Fab")
		)
		(fp_line
			(start -0.12065 0.2794)
			(end -0.12065 0.3048)
			(stroke
				(width 0.1)
				(type default)
			)
			(layer "F.Fab")
		)
		(fp_line
			(start -0.12065 -0.2794)
			(end 0.12065 -0.2794)
			(stroke
				(width 0.1)
				(type default)
			)
			(layer "F.Fab")
		)
		(fp_line
			(start -0.12065 -0.305054)
			(end -0.12065 -0.2794)
			(stroke
				(width 0.1)
				(type default)
			)
			(layer "F.Fab")
		)
		(fp_line
			(start -0.67945 0.3048)
			(end -0.67945 -0.305054)
			(stroke
				(width 0.1)
				(type default)
			)
			(layer "F.Fab")
		)
		(fp_line
			(start -0.67945 -0.305054)
			(end -0.12065 -0.305054)
			(stroke
				(width 0.1)
				(type default)
			)
			(layer "F.Fab")
		)
		(pad "1" smd circle
			(at -0.40005 0 180)
			(size 0 0)
			(layers "F.Cu" "F.Mask" "F.Paste")
			(net "SPI_SYS_R1_CLK")
		)
		(pad "2" smd circle
			(at 0.40005 0 180)
			(size 0 0)
			(layers "F.Cu" "F.Mask" "F.Paste")
			(net "SPI_SYS_R_CLK")
		)
	)
	(footprint ""
		(layer "F.Cu")
		(at 36.399978 -25.619964)
		(property "Reference" "J8"
			(at -1.779778 -8.338566 0)
			(unlocked yes)
			(layer "F.SilkS")
			(effects
				(font
					(size 0.7874 0.5842)
					(thickness 0.1524)
				)
				(justify left)
			)
		)
		(property "Value" ""
			(at 0 0 0)
			(layer "F.Fab")
			(effects
				(font
					(size 1.27 1.27)
				)
			)
		)
		(duplicate_pad_numbers_are_jumpers no)
		(fp_line
			(start -1.450086 -7.549896)
			(end -1.450086 -6.4516)
			(stroke
				(width 0.1524)
				(type default)
			)
			(layer "F.SilkS")
		)
		(fp_line
			(start -1.450086 6.4516)
			(end -1.450086 7.549896)
			(stroke
				(width 0.1524)
				(type default)
			)
			(layer "F.SilkS")
		)
		(fp_line
			(start -1.450086 7.549896)
			(end -0.2794 7.549896)
			(stroke
				(width 0.1524)
				(type default)
			)
			(layer "F.SilkS")
		)
		(fp_line
			(start -0.2794 -7.549896)
			(end -1.450086 -7.549896)
			(stroke
				(width 0.1524)
				(type default)
			)
			(layer "F.SilkS")
		)
		(fp_line
			(start 1.450086 6.5532)
			(end 1.450086 -6.5532)
			(stroke
				(width 0.1524)
				(type default)
			)
			(layer "F.SilkS")
		)
		(fp_poly
			(pts
				(xy -3.7084 -5.491988) (xy -3.7084 -6.507988) (xy -2.6924 -5.999988)
			)
			(stroke
				(width 0)
				(type default)
			)
			(fill yes)
			(layer "F.SilkS")
		)
		(fp_line
			(start -1.450086 -7.549896)
			(end -1.450086 7.549896)
			(stroke
				(width 0.1)
				(type default)
			)
			(layer "F.Fab")
		)
		(fp_line
			(start -1.450086 7.549896)
			(end 1.450086 7.549896)
			(stroke
				(width 0.1)
				(type default)
			)
			(layer "F.Fab")
		)
		(fp_line
			(start 1.450086 -7.549896)
			(end -1.450086 -7.549896)
			(stroke
				(width 0.1)
				(type default)
			)
			(layer "F.Fab")
		)
		(fp_line
			(start 1.450086 7.549896)
			(end 1.450086 -7.549896)
			(stroke
				(width 0.1)
				(type default)
			)
			(layer "F.Fab")
		)
		(fp_poly
			(pts
				(xy -3.7084 -5.491988) (xy -3.7084 -6.507988) (xy -2.6924 -5.999988)
			)
			(stroke
				(width 0)
				(type default)
			)
			(fill yes)
			(layer "F.Fab")
		)
		(fp_text user "13"
			(at -3.235452 5.9944 270)
			(unlocked yes)
			(layer "F.SilkS")
			(effects
				(font
					(size 0.7874 0.5842)
					(thickness 0.1524)
				)
			)
		)
		(fp_text user "13"
			(at -3.235452 5.9944 270)
			(unlocked yes)
			(layer "F.Fab")
			(effects
				(font
					(size 0.7874 0.5842)
					(thickness 0.1524)
				)
			)
		)
		(pad "1" smd rect
			(at -1.774952 -5.999988 270)
			(size 0.6096 1.5494)
			(layers "F.Cu" "F.Mask" "F.Paste")
			(net "V_DACR_IO")
		)
		(pad "2" smd rect
			(at -1.774952 -4.99999 270)
			(size 0.6096 1.5494)
			(layers "F.Cu" "F.Mask" "F.Paste")
			(net "GND")
		)
		(pad "3" smd rect
			(at -1.774952 -3.999992 270)
			(size 0.6096 1.5494)
			(layers "F.Cu" "F.Mask" "F.Paste")
			(net "V_DACG_IO")
		)
		(pad "4" smd rect
			(at -1.774952 -2.999994 270)
			(size 0.6096 1.5494)
			(layers "F.Cu" "F.Mask" "F.Paste")
			(net "GND")
		)
		(pad "5" smd rect
			(at -1.774952 -1.999996 270)
			(size 0.6096 1.5494)
			(layers "F.Cu" "F.Mask" "F.Paste")
			(net "V_DACB_IO")
		)
		(pad "6" smd rect
			(at -1.774952 -0.999998 270)
			(size 0.6096 1.5494)
			(layers "F.Cu" "F.Mask" "F.Paste")
			(net "GND")
		)
		(pad "7" smd rect
			(at -1.774952 0 270)
			(size 0.6096 1.5494)
			(layers "F.Cu" "F.Mask" "F.Paste")
			(net "V_VGAVS_BUF")
		)
		(pad "8" smd rect
			(at -1.774952 0.999998 270)
			(size 0.6096 1.5494)
			(layers "F.Cu" "F.Mask" "F.Paste")
			(net "GND")
		)
		(pad "9" smd rect
			(at -1.774952 1.999996 270)
			(size 0.6096 1.5494)
			(layers "F.Cu" "F.Mask" "F.Paste")
			(net "V_VGAHS_BUF")
		)
		(pad "10" smd rect
			(at -1.774952 2.999994 270)
			(size 0.6096 1.5494)
			(layers "F.Cu" "F.Mask" "F.Paste")
			(net "GND")
		)
		(pad "11" smd rect
			(at -1.774952 3.999992 270)
			(size 0.6096 1.5494)
			(layers "F.Cu" "F.Mask" "F.Paste")
			(net "V_BMC_LS_DDC_SDA_R")
		)
		(pad "12" smd rect
			(at -1.774952 4.99999 270)
			(size 0.6096 1.5494)
			(layers "F.Cu" "F.Mask" "F.Paste")
			(net "V_BMC_LS_DDC_SCL_R")
		)
		(pad "13" smd rect
			(at -1.774952 5.999988 270)
			(size 0.6096 1.5494)
			(layers "F.Cu" "F.Mask" "F.Paste")
			(net "CRT_VCC5_2_FUSE")
		)
		(pad "G1" smd rect
			(at 0.750062 -7.29996 270)
			(size 1.2192 1.8034)
			(layers "F.Cu" "F.Mask" "F.Paste")
			(net "GND")
		)
		(pad "G2" smd rect
			(at 0.750062 7.29996 270)
			(size 1.2192 1.8034)
			(layers "F.Cu" "F.Mask" "F.Paste")
			(net "GND")
		)
	)
	(footprint ""
		(layer "F.Cu")
		(at 73.980294 -98.425 180)
		(property "Reference" "R47"
			(at 0 0 180)
			(layer "F.SilkS")
			(hide yes)
			(effects
				(font
					(size 1.27 1.27)
				)
			)
		)
		(property "Value" ""
			(at 0 0 180)
			(layer "F.Fab")
			(effects
				(font
					(size 1.27 1.27)
				)
			)
		)
		(duplicate_pad_numbers_are_jumpers no)
		(fp_line
			(start 0.7874 0.4064)
			(end -0.7874 0.4064)
			(stroke
				(width 0.1524)
				(type default)
			)
			(layer "F.SilkS")
		)
		(fp_line
			(start 0.7874 -0.4064)
			(end 0.7874 0.4064)
			(stroke
				(width 0.1524)
				(type default)
			)
			(layer "F.SilkS")
		)
		(fp_line
			(start -0.7874 0.4064)
			(end -0.7874 -0.4064)
			(stroke
				(width 0.1524)
				(type default)
			)
			(layer "F.SilkS")
		)
		(fp_line
			(start -0.7874 -0.4064)
			(end 0.7874 -0.4064)
			(stroke
				(width 0.1524)
				(type default)
			)
			(layer "F.SilkS")
		)
		(fp_line
			(start 0.67945 0.3048)
			(end 0.120396 0.3048)
			(stroke
				(width 0.1)
				(type default)
			)
			(layer "F.Fab")
		)
		(fp_line
			(start 0.67945 -0.3048)
			(end 0.67945 0.3048)
			(stroke
				(width 0.1)
				(type default)
			)
			(layer "F.Fab")
		)
		(fp_line
			(start 0.12065 -0.2794)
			(end 0.12065 -0.3048)
			(stroke
				(width 0.1)
				(type default)
			)
			(layer "F.Fab")
		)
		(fp_line
			(start 0.12065 -0.3048)
			(end 0.67945 -0.3048)
			(stroke
				(width 0.1)
				(type default)
			)
			(layer "F.Fab")
		)
		(fp_line
			(start 0.120396 0.3048)
			(end 0.120396 0.2794)
			(stroke
				(width 0.1)
				(type default)
			)
			(layer "F.Fab")
		)
		(fp_line
			(start 0.120396 0.2794)
			(end -0.12065 0.2794)
			(stroke
				(width 0.1)
				(type default)
			)
			(layer "F.Fab")
		)
		(fp_line
			(start -0.12065 0.3048)
			(end -0.67945 0.3048)
			(stroke
				(width 0.1)
				(type default)
			)
			(layer "F.Fab")
		)
		(fp_line
			(start -0.12065 0.2794)
			(end -0.12065 0.3048)
			(stroke
				(width 0.1)
				(type default)
			)
			(layer "F.Fab")
		)
		(fp_line
			(start -0.12065 -0.2794)
			(end 0.12065 -0.2794)
			(stroke
				(width 0.1)
				(type default)
			)
			(layer "F.Fab")
		)
		(fp_line
			(start -0.12065 -0.305054)
			(end -0.12065 -0.2794)
			(stroke
				(width 0.1)
				(type default)
			)
			(layer "F.Fab")
		)
		(fp_line
			(start -0.67945 0.3048)
			(end -0.67945 -0.305054)
			(stroke
				(width 0.1)
				(type default)
			)
			(layer "F.Fab")
		)
		(fp_line
			(start -0.67945 -0.305054)
			(end -0.12065 -0.305054)
			(stroke
				(width 0.1)
				(type default)
			)
			(layer "F.Fab")
		)
		(pad "1" smd circle
			(at -0.40005 0 180)
			(size 0 0)
			(layers "F.Cu" "F.Mask" "F.Paste")
			(net "SMB_BMC_TPM_MM16_SCL")
		)
		(pad "2" smd circle
			(at 0.40005 0 180)
			(size 0 0)
			(layers "F.Cu" "F.Mask" "F.Paste")
			(net "SMB_BMC_MM16_R5_SCL")
		)
	)
)
